(kicad_pcb
	(version 20260206)
	(generator "pcbnew")
	(generator_version "10.0")
	(general
		(thickness 1.6)
		(legacy_teardrops no)
	)
	(paper "A4")
	(title_block
		(title "peb — Lightning_PEB_BRD.brd")
		(comment 1 "Lightning (Wiwynn / Facebook NVMe JBOF) / footprints 609-617 of 2563")
	)
	(layers
		(0 "F.Cu" signal "TOP")
		(4 "In1.Cu" signal "L2GND")
		(6 "In2.Cu" signal "L3")
		(8 "In3.Cu" signal "L4VCC")
		(10 "In4.Cu" signal "L5VCC")
		(12 "In5.Cu" signal "L6")
		(14 "In6.Cu" signal "L7GND")
		(2 "B.Cu" signal "BOTTOM")
		(9 "F.Adhes" user "F.Adhesive")
		(11 "B.Adhes" user "B.Adhesive")
		(13 "F.Paste" user "Package Geometry/Pastemask Top")
		(15 "B.Paste" user "Package Geometry/Pastemask Bottom")
		(5 "F.SilkS" user "Ref Des/Silkscreen Top")
		(7 "B.SilkS" user "Ref Des/Silkscreen Bottom")
		(1 "F.Mask" user "Board Geometry/Soldermask Top")
		(3 "B.Mask" user "Board Geometry/Soldermask Bottom")
		(17 "Dwgs.User" user "User.Drawings")
		(19 "Cmts.User" user "User.Comments")
		(21 "Eco1.User" user "User.Eco1")
		(23 "Eco2.User" user "User.Eco2")
		(25 "Edge.Cuts" user "Board Geometry/Outline")
		(27 "Margin" user)
		(31 "F.CrtYd" user "Package Geometry/Place Bound Top")
		(29 "B.CrtYd" user "Package Geometry/Place Bound Bottom")
		(35 "F.Fab" user "Ref Des/Assembly Top")
		(33 "B.Fab" user "Ref Des/Assembly Bottom")
	)
	(footprint ""
		(layer "F.Cu")
		(at 336.8294 -186.9186 180)
		(property "Reference" "R9043"
			(at 0 0 180)
			(layer "F.SilkS")
			(hide yes)
			(effects
				(font
					(size 1.27 1.27)
				)
			)
		)
		(property "Value" "4K7R2F-GP"
			(at 0.064008 -3.993896 180)
			(unlocked yes)
			(layer "F.Fab")
			(hide yes)
			(effects
				(font
					(size 1.016 1.016)
					(thickness 0.1524)
				)
			)
		)
		(property "Device Type" "R402H16"
			(at 0.064008 -5.517896 180)
			(unlocked yes)
			(layer "F.Fab")
			(hide yes)
			(effects
				(font
					(size 1.016 1.016)
					(thickness 0.1524)
				)
			)
		)
		(duplicate_pad_numbers_are_jumpers no)
		(fp_line
			(start 0.508 -0.9398)
			(end -0.508 -0.9398)
			(stroke
				(width 0.1524)
				(type default)
			)
			(layer "F.SilkS")
		)
		(fp_line
			(start -0.508 -0.9398)
			(end -0.508 0.9398)
			(stroke
				(width 0.1524)
				(type default)
			)
			(layer "F.SilkS")
		)
		(fp_rect
			(start -0.508 0.9398)
			(end 0.508 -0.9398)
			(stroke
				(width 0)
				(type default)
			)
			(fill no)
			(layer "F.CrtYd")
		)
		(fp_rect
			(start -0.508 0.9398)
			(end 0.508 -0.9398)
			(stroke
				(width 0)
				(type default)
			)
			(fill no)
			(layer "F.Fab")
		)
		(pad "1" smd custom
			(at 0 -0.4445 180)
			(size 0.1397 0.1397)
			(layers "F.Cu" "F.Mask" "F.Paste")
			(net "SSD_PERST#14")
			(options
				(clearance outline)
				(anchor circle)
			)
			(primitives
				(gr_poly
					(pts
						(arc
							(start -0.1778 -0.2794)
							(mid -0.249642 -0.249642)
							(end -0.2794 -0.1778)
						)
						(arc
							(start -0.2794 0.1778)
							(mid -0.249642 0.249642)
							(end -0.1778 0.2794)
						)
						(arc
							(start 0.1778 0.2794)
							(mid 0.249642 0.249642)
							(end 0.2794 0.1778)
						)
						(arc
							(start 0.2794 -0.1778)
							(mid 0.249642 -0.249642)
							(end 0.1778 -0.2794)
						)
					)
					(width 0)
					(fill yes)
				)
			)
		)
		(pad "2" smd custom
			(at 0 0.4445 180)
			(size 0.1397 0.1397)
			(layers "F.Cu" "F.Mask" "F.Paste")
			(net "GND")
			(options
				(clearance outline)
				(anchor circle)
			)
			(primitives
				(gr_poly
					(pts
						(arc
							(start -0.1778 -0.2794)
							(mid -0.249642 -0.249642)
							(end -0.2794 -0.1778)
						)
						(arc
							(start -0.2794 0.1778)
							(mid -0.249642 0.249642)
							(end -0.1778 0.2794)
						)
						(arc
							(start 0.1778 0.2794)
							(mid 0.249642 0.249642)
							(end 0.2794 0.1778)
						)
						(arc
							(start 0.2794 -0.1778)
							(mid 0.249642 -0.249642)
							(end 0.1778 -0.2794)
						)
					)
					(width 0)
					(fill yes)
				)
			)
		)
	)
	(footprint ""
		(layer "F.Cu")
		(at 12.1412 -194.6656 180)
		(property "Reference" "C7317"
			(at 0 0 180)
			(layer "F.SilkS")
			(hide yes)
			(effects
				(font
					(size 1.27 1.27)
				)
			)
		)
		(property "Value" "SCD1U25V3JX-GP"
			(at 0 -2.8194 180)
			(unlocked yes)
			(layer "F.Fab")
			(hide yes)
			(effects
				(font
					(size 1.016 1.016)
					(thickness 0.1524)
				)
			)
		)
		(property "Device Type" "C603H36"
			(at 0 -4.3434 180)
			(unlocked yes)
			(layer "F.Fab")
			(hide yes)
			(effects
				(font
					(size 1.016 1.016)
					(thickness 0.1524)
				)
			)
		)
		(duplicate_pad_numbers_are_jumpers no)
		(fp_line
			(start 0.508 0)
			(end -0.508 0)
			(stroke
				(width 0.2032)
				(type default)
			)
			(layer "F.SilkS")
		)
		(fp_rect
			(start -0.5842 1.3335)
			(end 0.5842 -1.3335)
			(stroke
				(width 0)
				(type default)
			)
			(fill no)
			(layer "F.CrtYd")
		)
		(fp_rect
			(start -0.5842 1.3335)
			(end 0.5842 -1.3335)
			(stroke
				(width 0)
				(type default)
			)
			(fill no)
			(layer "F.Fab")
		)
		(pad "1" smd custom
			(at 0 -0.762 180)
			(size 0.2159 0.2159)
			(layers "F.Cu" "F.Mask" "F.Paste")
			(net "MB0_ISTART_R")
			(options
				(clearance outline)
				(anchor circle)
			)
			(primitives
				(gr_poly
					(pts
						(arc
							(start -0.3302 -0.4318)
							(mid -0.402042 -0.402042)
							(end -0.4318 -0.3302)
						)
						(arc
							(start -0.4318 0.3302)
							(mid -0.402042 0.402042)
							(end -0.3302 0.4318)
						)
						(arc
							(start 0.3302 0.4318)
							(mid 0.402042 0.402042)
							(end 0.4318 0.3302)
						)
						(arc
							(start 0.4318 -0.3302)
							(mid 0.402042 -0.402042)
							(end 0.3302 -0.4318)
						)
					)
					(width 0)
					(fill yes)
				)
			)
		)
		(pad "2" smd custom
			(at 0 0.762 180)
			(size 0.2159 0.2159)
			(layers "F.Cu" "F.Mask" "F.Paste")
			(net "AGND_CURRENT_MON")
			(options
				(clearance outline)
				(anchor circle)
			)
			(primitives
				(gr_poly
					(pts
						(arc
							(start -0.3302 -0.4318)
							(mid -0.402042 -0.402042)
							(end -0.4318 -0.3302)
						)
						(arc
							(start -0.4318 0.3302)
							(mid -0.402042 0.402042)
							(end -0.3302 0.4318)
						)
						(arc
							(start 0.3302 0.4318)
							(mid 0.402042 0.402042)
							(end 0.4318 0.3302)
						)
						(arc
							(start 0.4318 -0.3302)
							(mid 0.402042 -0.402042)
							(end 0.3302 -0.4318)
						)
					)
					(width 0)
					(fill yes)
				)
			)
		)
	)
	(footprint ""
		(layer "F.Cu")
		(at 289.179 -33.528)
		(property "Reference" "C10"
			(at 0 0 0)
			(layer "F.SilkS")
			(hide yes)
			(effects
				(font
					(size 1.27 1.27)
				)
			)
		)
		(property "Value" "SCD22U10V2KX-1GP"
			(at 1.1811 -2.7051 0)
			(unlocked yes)
			(layer "F.Fab")
			(hide yes)
			(effects
				(font
					(size 1.016 1.016)
					(thickness 0.1524)
				)
			)
		)
		(property "Device Type" "C402H22"
			(at 1.1811 -4.2291 0)
			(unlocked yes)
			(layer "F.Fab")
			(hide yes)
			(effects
				(font
					(size 1.016 1.016)
					(thickness 0.1524)
				)
			)
		)
		(duplicate_pad_numbers_are_jumpers no)
		(fp_rect
			(start -0.4318 0.9525)
			(end 0.4318 -0.9525)
			(stroke
				(width 0)
				(type default)
			)
			(fill no)
			(layer "F.CrtYd")
		)
		(fp_rect
			(start -0.4318 0.9525)
			(end 0.4318 -0.9525)
			(stroke
				(width 0)
				(type default)
			)
			(fill no)
			(layer "F.Fab")
		)
		(pad "1" smd custom
			(at 0 -0.4445)
			(size 0.1524 0.1524)
			(layers "F.Cu" "F.Mask" "F.Paste")
			(net "PCIE_TX_CAP_P3")
			(options
				(clearance outline)
				(anchor circle)
			)
			(primitives
				(gr_poly
					(pts
						(arc
							(start 0.3048 -0.2032)
							(mid 0.275042 -0.275042)
							(end 0.2032 -0.3048)
						)
						(arc
							(start -0.2032 -0.3048)
							(mid -0.275042 -0.275042)
							(end -0.3048 -0.2032)
						)
						(arc
							(start -0.3048 0.2032)
							(mid -0.275042 0.275042)
							(end -0.2032 0.3048)
						)
						(arc
							(start 0.2032 0.3048)
							(mid 0.275042 0.275042)
							(end 0.3048 0.2032)
						)
					)
					(width 0)
					(fill yes)
				)
			)
		)
		(pad "2" smd custom
			(at 0 0.4445)
			(size 0.1524 0.1524)
			(layers "F.Cu" "F.Mask" "F.Paste")
			(net "PCIE_TX_P3")
			(options
				(clearance outline)
				(anchor circle)
			)
			(primitives
				(gr_poly
					(pts
						(arc
							(start 0.3048 -0.2032)
							(mid 0.275042 -0.275042)
							(end 0.2032 -0.3048)
						)
						(arc
							(start -0.2032 -0.3048)
							(mid -0.275042 -0.275042)
							(end -0.3048 -0.2032)
						)
						(arc
							(start -0.3048 0.2032)
							(mid -0.275042 0.275042)
							(end -0.2032 0.3048)
						)
						(arc
							(start 0.2032 0.3048)
							(mid 0.275042 0.275042)
							(end 0.3048 0.2032)
						)
					)
					(width 0)
					(fill yes)
				)
			)
		)
	)
	(footprint ""
		(layer "F.Cu")
		(at 178.1048 -69.215 180)
		(property "Reference" "PG19"
			(at 0 0 180)
			(layer "F.SilkS")
			(hide yes)
			(effects
				(font
					(size 1.27 1.27)
				)
			)
		)
		(property "Value" "GAP-CLOSE-PWR-3-GP"
			(at 0.0254 -6.5786 180)
			(unlocked yes)
			(layer "F.Fab")
			(hide yes)
			(effects
				(font
					(size 1.016 1.016)
					(thickness 0.1524)
				)
			)
		)
		(property "Device Type" "GAP-CLOSE-PWR-3"
			(at 0.0254 -8.255 180)
			(unlocked yes)
			(layer "F.Fab")
			(hide yes)
			(effects
				(font
					(size 1.016 1.016)
					(thickness 0.1524)
				)
			)
		)
		(duplicate_pad_numbers_are_jumpers no)
		(fp_rect
			(start -0.7112 0.4572)
			(end 0.7112 -0.4572)
			(stroke
				(width 0)
				(type default)
			)
			(fill no)
			(layer "F.CrtYd")
		)
		(fp_poly
			(pts
				(xy -0.7112 -0.4572) (xy 0.7112 -0.4572) (xy 0.7112 0.4572) (xy -0.7112 0.4572)
			)
			(stroke
				(width 0)
				(type default)
			)
			(fill no)
			(layer "F.Fab")
		)
		(pad "1" smd rect
			(at -0.3048 0 180)
			(size 0.6604 0.762)
			(layers "F.Cu" "F.Mask" "F.Paste")
			(net "DUT_AVD_PCIE")
		)
		(pad "2" smd rect
			(at 0.3048 0 180)
			(size 0.6604 0.762)
			(layers "F.Cu" "F.Mask" "F.Paste")
			(net "P0V9")
		)
	)
	(footprint ""
		(layer "F.Cu")
		(at 142.608046 -212.420454 180)
		(property "Reference" "C341"
			(at 0 0 180)
			(layer "F.SilkS")
			(hide yes)
			(effects
				(font
					(size 1.27 1.27)
				)
			)
		)
		(property "Value" "SCD22U10V2KX-1GP"
			(at 1.1811 -2.7051 180)
			(unlocked yes)
			(layer "F.Fab")
			(hide yes)
			(effects
				(font
					(size 1.016 1.016)
					(thickness 0.1524)
				)
			)
		)
		(property "Device Type" "C402H22"
			(at 1.1811 -4.2291 180)
			(unlocked yes)
			(layer "F.Fab")
			(hide yes)
			(effects
				(font
					(size 1.016 1.016)
					(thickness 0.1524)
				)
			)
		)
		(duplicate_pad_numbers_are_jumpers no)
		(fp_rect
			(start -0.4318 0.9525)
			(end 0.4318 -0.9525)
			(stroke
				(width 0)
				(type default)
			)
			(fill no)
			(layer "F.CrtYd")
		)
		(fp_rect
			(start -0.4318 0.9525)
			(end 0.4318 -0.9525)
			(stroke
				(width 0)
				(type default)
			)
			(fill no)
			(layer "F.Fab")
		)
		(pad "1" smd custom
			(at 0 -0.4445 180)
			(size 0.1524 0.1524)
			(layers "F.Cu" "F.Mask" "F.Paste")
			(net "PCIE_TX_CAP_N58")
			(options
				(clearance outline)
				(anchor circle)
			)
			(primitives
				(gr_poly
					(pts
						(arc
							(start 0.3048 -0.2032)
							(mid 0.275042 -0.275042)
							(end 0.2032 -0.3048)
						)
						(arc
							(start -0.2032 -0.3048)
							(mid -0.275042 -0.275042)
							(end -0.3048 -0.2032)
						)
						(arc
							(start -0.3048 0.2032)
							(mid -0.275042 0.275042)
							(end -0.2032 0.3048)
						)
						(arc
							(start 0.2032 0.3048)
							(mid 0.275042 0.275042)
							(end 0.3048 0.2032)
						)
					)
					(width 0)
					(fill yes)
				)
			)
		)
		(pad "2" smd custom
			(at 0 0.4445 180)
			(size 0.1524 0.1524)
			(layers "F.Cu" "F.Mask" "F.Paste")
			(net "PCIE_TX_N58")
			(options
				(clearance outline)
				(anchor circle)
			)
			(primitives
				(gr_poly
					(pts
						(arc
							(start 0.3048 -0.2032)
							(mid 0.275042 -0.275042)
							(end 0.2032 -0.3048)
						)
						(arc
							(start -0.2032 -0.3048)
							(mid -0.275042 -0.275042)
							(end -0.3048 -0.2032)
						)
						(arc
							(start -0.3048 0.2032)
							(mid -0.275042 0.275042)
							(end -0.2032 0.3048)
						)
						(arc
							(start 0.2032 0.3048)
							(mid 0.275042 0.275042)
							(end 0.3048 0.2032)
						)
					)
					(width 0)
					(fill yes)
				)
			)
		)
	)
	(footprint ""
		(layer "F.Cu")
		(at 25.908 -126.4158)
		(property "Reference" "TP236"
			(at 0 0 0)
			(layer "F.SilkS")
			(hide yes)
			(effects
				(font
					(size 1.27 1.27)
				)
			)
		)
		(property "Value" "TPAD28-2-GP"
			(at -0.0127 -1.6637 0)
			(unlocked yes)
			(layer "F.Fab")
			(hide yes)
			(effects
				(font
					(size 1.016 1.016)
					(thickness 0.1524)
				)
			)
		)
		(property "Device Type" "TPAD28"
			(at -0.0127 -3.1877 0)
			(unlocked yes)
			(layer "F.Fab")
			(hide yes)
			(effects
				(font
					(size 1.016 1.016)
					(thickness 0.1524)
				)
			)
		)
		(duplicate_pad_numbers_are_jumpers no)
		(fp_poly
			(pts
				(arc
					(start 0.3556 0)
					(mid -0.3556 0)
					(end 0.3556 0)
				)
			)
			(stroke
				(width 0)
				(type default)
			)
			(fill no)
			(layer "F.CrtYd")
		)
		(fp_poly
			(pts
				(arc
					(start 0.6096 0)
					(mid -0.6096 0)
					(end 0.6096 0)
				)
			)
			(stroke
				(width 0)
				(type default)
			)
			(fill no)
			(layer "F.Fab")
		)
		(pad "1" smd circle
			(at 0 0)
			(size 0.7112 0.7112)
			(layers "F.Cu" "F.Mask" "F.Paste")
			(net "TP_GPIOY3")
		)
	)
	(footprint ""
		(layer "F.Cu")
		(at 75.623166 -90.58656 180)
		(property "Reference" "C263"
			(at 0 0 180)
			(layer "F.SilkS")
			(hide yes)
			(effects
				(font
					(size 1.27 1.27)
				)
			)
		)
		(property "Value" "SCD1U16V2KX-3GP"
			(at 1.1811 -2.7051 180)
			(unlocked yes)
			(layer "F.Fab")
			(hide yes)
			(effects
				(font
					(size 1.016 1.016)
					(thickness 0.1524)
				)
			)
		)
		(property "Device Type" "C402H22"
			(at 1.1811 -4.2291 180)
			(unlocked yes)
			(layer "F.Fab")
			(hide yes)
			(effects
				(font
					(size 1.016 1.016)
					(thickness 0.1524)
				)
			)
		)
		(duplicate_pad_numbers_are_jumpers no)
		(fp_rect
			(start -0.4318 0.9525)
			(end 0.4318 -0.9525)
			(stroke
				(width 0)
				(type default)
			)
			(fill no)
			(layer "F.CrtYd")
		)
		(fp_rect
			(start -0.4318 0.9525)
			(end 0.4318 -0.9525)
			(stroke
				(width 0)
				(type default)
			)
			(fill no)
			(layer "F.Fab")
		)
		(pad "1" smd custom
			(at 0 -0.4445 180)
			(size 0.1524 0.1524)
			(layers "F.Cu" "F.Mask" "F.Paste")
			(net "P3V3_STBY")
			(options
				(clearance outline)
				(anchor circle)
			)
			(primitives
				(gr_poly
					(pts
						(arc
							(start 0.3048 -0.2032)
							(mid 0.275042 -0.275042)
							(end 0.2032 -0.3048)
						)
						(arc
							(start -0.2032 -0.3048)
							(mid -0.275042 -0.275042)
							(end -0.3048 -0.2032)
						)
						(arc
							(start -0.3048 0.2032)
							(mid -0.275042 0.275042)
							(end -0.2032 0.3048)
						)
						(arc
							(start 0.2032 0.3048)
							(mid 0.275042 0.275042)
							(end 0.3048 0.2032)
						)
					)
					(width 0)
					(fill yes)
				)
			)
		)
		(pad "2" smd custom
			(at 0 0.4445 180)
			(size 0.1524 0.1524)
			(layers "F.Cu" "F.Mask" "F.Paste")
			(net "GND")
			(options
				(clearance outline)
				(anchor circle)
			)
			(primitives
				(gr_poly
					(pts
						(arc
							(start 0.3048 -0.2032)
							(mid 0.275042 -0.275042)
							(end 0.2032 -0.3048)
						)
						(arc
							(start -0.2032 -0.3048)
							(mid -0.275042 -0.275042)
							(end -0.3048 -0.2032)
						)
						(arc
							(start -0.3048 0.2032)
							(mid -0.275042 0.275042)
							(end -0.2032 0.3048)
						)
						(arc
							(start 0.2032 0.3048)
							(mid 0.275042 0.275042)
							(end 0.3048 0.2032)
						)
					)
					(width 0)
					(fill yes)
				)
			)
		)
	)
	(footprint ""
		(layer "F.Cu")
		(at 270.792194 -212.420454 180)
		(property "Reference" "C103"
			(at 0 0 180)
			(layer "F.SilkS")
			(hide yes)
			(effects
				(font
					(size 1.27 1.27)
				)
			)
		)
		(property "Value" "SCD22U10V2KX-1GP"
			(at 1.1811 -2.7051 180)
			(unlocked yes)
			(layer "F.Fab")
			(hide yes)
			(effects
				(font
					(size 1.016 1.016)
					(thickness 0.1524)
				)
			)
		)
		(property "Device Type" "C402H22"
			(at 1.1811 -4.2291 180)
			(unlocked yes)
			(layer "F.Fab")
			(hide yes)
			(effects
				(font
					(size 1.016 1.016)
					(thickness 0.1524)
				)
			)
		)
		(duplicate_pad_numbers_are_jumpers no)
		(fp_rect
			(start -0.4318 0.9525)
			(end 0.4318 -0.9525)
			(stroke
				(width 0)
				(type default)
			)
			(fill no)
			(layer "F.CrtYd")
		)
		(fp_rect
			(start -0.4318 0.9525)
			(end 0.4318 -0.9525)
			(stroke
				(width 0)
				(type default)
			)
			(fill no)
			(layer "F.Fab")
		)
		(pad "1" smd custom
			(at 0 -0.4445 180)
			(size 0.1524 0.1524)
			(layers "F.Cu" "F.Mask" "F.Paste")
			(net "PCIE_TX_CAP_P35")
			(options
				(clearance outline)
				(anchor circle)
			)
			(primitives
				(gr_poly
					(pts
						(arc
							(start 0.3048 -0.2032)
							(mid 0.275042 -0.275042)
							(end 0.2032 -0.3048)
						)
						(arc
							(start -0.2032 -0.3048)
							(mid -0.275042 -0.275042)
							(end -0.3048 -0.2032)
						)
						(arc
							(start -0.3048 0.2032)
							(mid -0.275042 0.275042)
							(end -0.2032 0.3048)
						)
						(arc
							(start 0.2032 0.3048)
							(mid 0.275042 0.275042)
							(end 0.3048 0.2032)
						)
					)
					(width 0)
					(fill yes)
				)
			)
		)
		(pad "2" smd custom
			(at 0 0.4445 180)
			(size 0.1524 0.1524)
			(layers "F.Cu" "F.Mask" "F.Paste")
			(net "PCIE_TX_P35")
			(options
				(clearance outline)
				(anchor circle)
			)
			(primitives
				(gr_poly
					(pts
						(arc
							(start 0.3048 -0.2032)
							(mid 0.275042 -0.275042)
							(end 0.2032 -0.3048)
						)
						(arc
							(start -0.2032 -0.3048)
							(mid -0.275042 -0.275042)
							(end -0.3048 -0.2032)
						)
						(arc
							(start -0.3048 0.2032)
							(mid -0.275042 0.275042)
							(end -0.2032 0.3048)
						)
						(arc
							(start 0.2032 0.3048)
							(mid 0.275042 0.275042)
							(end 0.3048 0.2032)
						)
					)
					(width 0)
					(fill yes)
				)
			)
		)
	)
	(footprint ""
		(layer "F.Cu")
		(at 152.6032 -33.5026)
		(property "Reference" "C394"
			(at 0 0 0)
			(layer "F.SilkS")
			(hide yes)
			(effects
				(font
					(size 1.27 1.27)
				)
			)
		)
		(property "Value" "SCD22U10V2KX-1GP"
			(at 1.1811 -2.7051 0)
			(unlocked yes)
			(layer "F.Fab")
			(hide yes)
			(effects
				(font
					(size 1.016 1.016)
					(thickness 0.1524)
				)
			)
		)
		(property "Device Type" "C402H22"
			(at 1.1811 -4.2291 0)
			(unlocked yes)
			(layer "F.Fab")
			(hide yes)
			(effects
				(font
					(size 1.016 1.016)
					(thickness 0.1524)
				)
			)
		)
		(duplicate_pad_numbers_are_jumpers no)
		(fp_rect
			(start -0.4318 0.9525)
			(end 0.4318 -0.9525)
			(stroke
				(width 0)
				(type default)
			)
			(fill no)
			(layer "F.CrtYd")
		)
		(fp_rect
			(start -0.4318 0.9525)
			(end 0.4318 -0.9525)
			(stroke
				(width 0)
				(type default)
			)
			(fill no)
			(layer "F.Fab")
		)
		(pad "1" smd custom
			(at 0 -0.4445)
			(size 0.1524 0.1524)
			(layers "F.Cu" "F.Mask" "F.Paste")
			(net "PCIE_TX_CAP_P87")
			(options
				(clearance outline)
				(anchor circle)
			)
			(primitives
				(gr_poly
					(pts
						(arc
							(start 0.3048 -0.2032)
							(mid 0.275042 -0.275042)
							(end 0.2032 -0.3048)
						)
						(arc
							(start -0.2032 -0.3048)
							(mid -0.275042 -0.275042)
							(end -0.3048 -0.2032)
						)
						(arc
							(start -0.3048 0.2032)
							(mid -0.275042 0.275042)
							(end -0.2032 0.3048)
						)
						(arc
							(start 0.2032 0.3048)
							(mid 0.275042 0.275042)
							(end 0.3048 0.2032)
						)
					)
					(width 0)
					(fill yes)
				)
			)
		)
		(pad "2" smd custom
			(at 0 0.4445)
			(size 0.1524 0.1524)
			(layers "F.Cu" "F.Mask" "F.Paste")
			(net "PCIE_TX_P87")
			(options
				(clearance outline)
				(anchor circle)
			)
			(primitives
				(gr_poly
					(pts
						(arc
							(start 0.3048 -0.2032)
							(mid 0.275042 -0.275042)
							(end 0.2032 -0.3048)
						)
						(arc
							(start -0.2032 -0.3048)
							(mid -0.275042 -0.275042)
							(end -0.3048 -0.2032)
						)
						(arc
							(start -0.3048 0.2032)
							(mid -0.275042 0.275042)
							(end -0.2032 0.3048)
						)
						(arc
							(start 0.2032 0.3048)
							(mid 0.275042 0.275042)
							(end 0.3048 0.2032)
						)
					)
					(width 0)
					(fill yes)
				)
			)
		)
	)
)
